(kicad_pcb
	(version 20241229)
	(generator "pcbnew")
	(generator_version "9.0")
	(general
		(thickness 1.6)
		(legacy_teardrops no)
	)
	(paper "A4")
	(title_block
		(title "OCuLink to PCIe adapter")
		(date "2025-06-18")
		(rev "1.0.0")
		(company "Antmicro Ltd")
		(comment 1 "www.antmicro.com")
		(comment 9 "footprints 10-13 of 159")
	)
	(layers
		(0 "F.Cu" signal)
		(4 "In1.Cu" signal)
		(6 "In2.Cu" signal)
		(2 "B.Cu" signal)
		(9 "F.Adhes" user "F.Adhesive")
		(11 "B.Adhes" user "B.Adhesive")
		(13 "F.Paste" user)
		(15 "B.Paste" user)
		(5 "F.SilkS" user "F.Silkscreen")
		(7 "B.SilkS" user "B.Silkscreen")
		(1 "F.Mask" user)
		(3 "B.Mask" user)
		(17 "Dwgs.User" user "User.Drawings")
		(19 "Cmts.User" user "User.Comments")
		(21 "Eco1.User" user "User.Eco1")
		(23 "Eco2.User" user "User.Eco2")
		(25 "Edge.Cuts" user)
		(27 "Margin" user)
		(31 "F.CrtYd" user "F.Courtyard")
		(29 "B.CrtYd" user "B.Courtyard")
		(35 "F.Fab" user)
		(33 "B.Fab" user)
	)
	(footprint "antmicro-footprints:R_0402_1005Metric"
		(layer "F.Cu")
		(at 153.900001 47.62 90)
		(descr "Resistor SMD 0402")
		(tags "resistor SMD 0402")
		(property "Reference" "R37"
			(at 1.02 3.699998 90)
			(layer "F.SilkS")
			(effects
				(font
					(size 0.7 0.7)
					(thickness 0.15)
				)
				(justify right top)
			)
		)
		(property "Value" "R_1k_0402"
			(at -1.011843 1.772046 90)
			(layer "F.Fab")
			(effects
				(font
					(size 0.7 0.7)
					(thickness 0.15)
				)
				(justify left bottom)
			)
		)
		(property "Datasheet" "https://www.bourns.com/docs/product-datasheets/cr.pdf"
			(at 0 0 90)
			(layer "F.Fab")
			(hide yes)
			(effects
				(font
					(size 1.27 1.27)
					(thickness 0.15)
				)
			)
		)
		(property "Description" "SMD Chip Resistor, 1 kohm, ± 1%, 63 mW, 0402 [1005 Metric], Thick Film, General Purpose"
			(at 0 0 90)
			(layer "F.Fab")
			(hide yes)
			(effects
				(font
					(size 1.27 1.27)
					(thickness 0.15)
				)
			)
		)
		(property "MPN" "CR0402-FX-1001GLF"
			(at 0 0 90)
			(unlocked yes)
			(layer "F.Fab")
			(hide yes)
			(effects
				(font
					(size 1 1)
					(thickness 0.15)
				)
			)
		)
		(property "Manufacturer" "Bourns"
			(at 0 0 90)
			(unlocked yes)
			(layer "F.Fab")
			(hide yes)
			(effects
				(font
					(size 1 1)
					(thickness 0.15)
				)
			)
		)
		(property "License" "Apache-2.0"
			(at 0 0 90)
			(unlocked yes)
			(layer "F.Fab")
			(hide yes)
			(effects
				(font
					(size 1 1)
					(thickness 0.15)
				)
			)
		)
		(property "Author" "Antmicro"
			(at 0 0 90)
			(unlocked yes)
			(layer "F.Fab")
			(hide yes)
			(effects
				(font
					(size 1 1)
					(thickness 0.15)
				)
			)
		)
		(property "Val" "1k"
			(at 0 0 90)
			(unlocked yes)
			(layer "F.Fab")
			(hide yes)
			(effects
				(font
					(size 1 1)
					(thickness 0.15)
				)
			)
		)
		(property "Tolerance" "1%"
			(at 0 0 90)
			(unlocked yes)
			(layer "F.Fab")
			(hide yes)
			(effects
				(font
					(size 1 1)
					(thickness 0.15)
				)
			)
		)
		(sheetname "/USB-PD/")
		(sheetfile "usb-pd.kicad_sch")
		(attr smd)
		(fp_rect
			(start -0.925 -0.47)
			(end 0.925 0.47)
			(stroke
				(width 0.05)
				(type default)
			)
			(fill no)
			(layer "F.CrtYd")
		)
		(fp_rect
			(start -0.5 -0.25)
			(end 0.5 0.25)
			(stroke
				(width 0.15)
				(type solid)
			)
			(fill no)
			(layer "F.Fab")
		)
		(fp_text user "License: Apache-2.0"
			(at -0.949999 5.169 90)
			(layer "F.Fab")
			(effects
				(font
					(size 0.7 0.7)
					(thickness 0.15)
				)
				(justify left bottom)
			)
		)
		(fp_text user "Author: Antmicro"
			(at -0.95 4.169 90)
			(layer "F.Fab")
			(effects
				(font
					(size 0.7 0.7)
					(thickness 0.15)
				)
				(justify left bottom)
			)
		)
		(fp_text user "${REFERENCE}"
			(at 0 0 270)
			(layer "F.Fab")
			(effects
				(font
					(size 0.7 0.7)
					(thickness 0.15)
				)
				(justify right top)
			)
		)
		(pad "1" smd roundrect
			(at -0.48 0 90)
			(size 0.59 0.64)
			(layers "F.Cu" "F.Mask" "F.Paste")
			(roundrect_rratio 0.25)
			(net 154 "/USB-PD/VBUS_EN")
			(pintype "passive")
		)
		(pad "2" smd roundrect
			(at 0.48 0 90)
			(size 0.59 0.64)
			(layers "F.Cu" "F.Mask" "F.Paste")
			(roundrect_rratio 0.25)
			(net 84 "Net-(Q6-G)")
			(pintype "passive")
		)
	)
	(footprint "antmicro-footprints:C_0805_2012Metric"
		(layer "F.Cu")
		(at 138.2 89.5 90)
		(descr "Capacitor SMD 0805")
		(tags "capacitor SMD 0805")
		(property "Reference" "C25"
			(at 0.3 -4.8 90)
			(layer "F.SilkS")
			(effects
				(font
					(size 0.7 0.7)
					(thickness 0.15)
				)
				(justify left bottom)
			)
		)
		(property "Value" "C_10u_0805_35V"
			(at -2.055717 1.963153 90)
			(layer "F.Fab")
			(effects
				(font
					(size 0.7 0.7)
					(thickness 0.15)
				)
				(justify left bottom)
			)
		)
		(property "Datasheet" "https://www.murata.com/products/productdetail?partno=GRM21BR6YA106KE43%23"
			(at 0 0 90)
			(layer "F.Fab")
			(hide yes)
			(effects
				(font
					(size 1.27 1.27)
					(thickness 0.15)
				)
			)
		)
		(property "Description" "SMD Multilayer Ceramic Capacitor, 10 µF, 35 V, 0805 [2012 Metric], ± 10%, X5R, GRM Series"
			(at 0 0 90)
			(layer "F.Fab")
			(hide yes)
			(effects
				(font
					(size 1.27 1.27)
					(thickness 0.15)
				)
			)
		)
		(property "MPN" "GRM21BR6YA106KE43L"
			(at 0 0 90)
			(unlocked yes)
			(layer "F.Fab")
			(hide yes)
			(effects
				(font
					(size 1 1)
					(thickness 0.15)
				)
			)
		)
		(property "Manufacturer" "Murata"
			(at 0 0 90)
			(unlocked yes)
			(layer "F.Fab")
			(hide yes)
			(effects
				(font
					(size 1 1)
					(thickness 0.15)
				)
			)
		)
		(property "License" "Apache-2.0"
			(at 0 0 90)
			(unlocked yes)
			(layer "F.Fab")
			(hide yes)
			(effects
				(font
					(size 1 1)
					(thickness 0.15)
				)
			)
		)
		(property "Author" "Antmicro"
			(at 0 0 90)
			(unlocked yes)
			(layer "F.Fab")
			(hide yes)
			(effects
				(font
					(size 1 1)
					(thickness 0.15)
				)
			)
		)
		(property "Val" "10u"
			(at 0 0 90)
			(unlocked yes)
			(layer "F.Fab")
			(hide yes)
			(effects
				(font
					(size 1 1)
					(thickness 0.15)
				)
			)
		)
		(property "Voltage" "35V"
			(at 0 0 90)
			(unlocked yes)
			(layer "F.Fab")
			(hide yes)
			(effects
				(font
					(size 1 1)
					(thickness 0.15)
				)
			)
		)
		(property "Dielectric" ""
			(at 0 0 90)
			(unlocked yes)
			(layer "F.Fab")
			(hide yes)
			(effects
				(font
					(size 1 1)
					(thickness 0.15)
				)
			)
		)
		(property "Public" "False"
			(at 0 0 90)
			(unlocked yes)
			(layer "F.Fab")
			(hide yes)
			(effects
				(font
					(size 1 1)
					(thickness 0.15)
				)
			)
		)
		(sheetname "/USB-PD/")
		(sheetfile "usb-pd.kicad_sch")
		(attr smd)
		(fp_line
			(start -0.3 -0.7)
			(end 0.3 -0.7)
			(stroke
				(width 0.15)
				(type solid)
			)
			(layer "F.SilkS")
		)
		(fp_line
			(start -0.3 0.7)
			(end 0.3 0.7)
			(stroke
				(width 0.15)
				(type solid)
			)
			(layer "F.SilkS")
		)
		(fp_rect
			(start 1.95 -0.9)
			(end -1.95 0.9)
			(stroke
				(width 0.05)
				(type default)
			)
			(fill no)
			(layer "F.CrtYd")
		)
		(fp_rect
			(start -0.95 -0.675)
			(end 0.95 0.675)
			(stroke
				(width 0.15)
				(type solid)
			)
			(fill no)
			(layer "F.Fab")
		)
		(fp_text user "License: Apache-2.0"
			(at -1.9 4.947 90)
			(layer "F.Fab")
			(effects
				(font
					(size 0.7 0.7)
					(thickness 0.15)
				)
				(justify left bottom)
			)
		)
		(fp_text user "${REFERENCE}"
			(at 0 0 90)
			(layer "F.Fab")
			(effects
				(font
					(size 0.7 0.7)
					(thickness 0.15)
				)
				(justify left bottom)
			)
		)
		(fp_text user "Author: Antmicro"
			(at -1.9 5.947 90)
			(layer "F.Fab")
			(effects
				(font
					(size 0.7 0.7)
					(thickness 0.15)
				)
				(justify left bottom)
			)
		)
		(pad "1" smd roundrect
			(at -1.1 0 90)
			(size 1.2 1.3)
			(layers "F.Cu" "F.Mask" "F.Paste")
			(roundrect_rratio 0.25)
			(net 66 "GND")
			(pintype "passive")
		)
		(pad "2" smd roundrect
			(at 1.1 0 90)
			(size 1.2 1.3)
			(layers "F.Cu" "F.Mask" "F.Paste")
			(roundrect_rratio 0.25)
			(net 115 "/USB-PD/VCC")
			(pintype "passive")
		)
	)
	(footprint "antmicro-footprints:C_0402_1005Metric"
		(layer "F.Cu")
		(at 146.562 53.001)
		(descr "Capacitor SMD 0402")
		(tags "capacitor SMD 0402")
		(property "Reference" "C41"
			(at -3.162 2.999 180)
			(layer "F.SilkS")
			(effects
				(font
					(size 0.7 0.7)
					(thickness 0.15)
				)
				(justify left bottom)
			)
		)
		(property "Value" "C_100n_0402"
			(at -1.022927 2.155213 0)
			(layer "F.Fab")
			(effects
				(font
					(size 0.7 0.7)
					(thickness 0.15)
				)
				(justify left bottom)
			)
		)
		(property "Datasheet" "https://www.murata.com/products/productdetail?partno=GRM155R61H104KE14%23"
			(at 0 0 0)
			(layer "F.Fab")
			(hide yes)
			(effects
				(font
					(size 1.27 1.27)
					(thickness 0.15)
				)
			)
		)
		(property "Description" "SMD Multilayer Ceramic Capacitor, 0.1 µF, 50 V, 0402 [1005 Metric], ± 10%, X5R, GRM Series"
			(at 0 0 0)
			(layer "F.Fab")
			(hide yes)
			(effects
				(font
					(size 1.27 1.27)
					(thickness 0.15)
				)
			)
		)
		(property "MPN" "GRM155R61H104KE14D"
			(at 0 0 0)
			(unlocked yes)
			(layer "F.Fab")
			(hide yes)
			(effects
				(font
					(size 1 1)
					(thickness 0.15)
				)
			)
		)
		(property "Manufacturer" "Murata"
			(at 0 0 0)
			(unlocked yes)
			(layer "F.Fab")
			(hide yes)
			(effects
				(font
					(size 1 1)
					(thickness 0.15)
				)
			)
		)
		(property "License" "Apache-2.0"
			(at 0 0 0)
			(unlocked yes)
			(layer "F.Fab")
			(hide yes)
			(effects
				(font
					(size 1 1)
					(thickness 0.15)
				)
			)
		)
		(property "Author" "Antmicro"
			(at 0 0 0)
			(unlocked yes)
			(layer "F.Fab")
			(hide yes)
			(effects
				(font
					(size 1 1)
					(thickness 0.15)
				)
			)
		)
		(property "Val" "100n"
			(at 0 0 0)
			(unlocked yes)
			(layer "F.Fab")
			(hide yes)
			(effects
				(font
					(size 1 1)
					(thickness 0.15)
				)
			)
		)
		(property "Voltage" "50V"
			(at 0 0 0)
			(unlocked yes)
			(layer "F.Fab")
			(hide yes)
			(effects
				(font
					(size 1 1)
					(thickness 0.15)
				)
			)
		)
		(property "Dielectric" "X5R"
			(at 0 0 0)
			(unlocked yes)
			(layer "F.Fab")
			(hide yes)
			(effects
				(font
					(size 1 1)
					(thickness 0.15)
				)
			)
		)
		(sheetname "/USB-PD/")
		(sheetfile "usb-pd.kicad_sch")
		(attr smd)
		(fp_rect
			(start -0.925 -0.47)
			(end 0.925 0.47)
			(stroke
				(width 0.05)
				(type default)
			)
			(fill no)
			(layer "F.CrtYd")
		)
		(fp_line
			(start -0.494 -0.25)
			(end 0.504 -0.25)
			(stroke
				(width 0.15)
				(type solid)
			)
			(layer "F.Fab")
		)
		(fp_line
			(start -0.494 0.248)
			(end -0.494 -0.25)
			(stroke
				(width 0.15)
				(type solid)
			)
			(layer "F.Fab")
		)
		(fp_line
			(start 0.504 -0.25)
			(end 0.504 0.248)
			(stroke
				(width 0.15)
				(type solid)
			)
			(layer "F.Fab")
		)
		(fp_line
			(start 0.504 0.248)
			(end -0.494 0.248)
			(stroke
				(width 0.15)
				(type solid)
			)
			(layer "F.Fab")
		)
		(fp_text user "Author: Antmicro"
			(at -0.939 3.399 0)
			(layer "F.Fab")
			(effects
				(font
					(size 0.7 0.7)
					(thickness 0.15)
				)
				(justify left bottom)
			)
		)
		(fp_text user "${REFERENCE}"
			(at 0 0 0)
			(layer "F.Fab")
			(effects
				(font
					(size 0.7 0.7)
					(thickness 0.15)
				)
				(justify left bottom)
			)
		)
		(fp_text user "License: Apache-2.0"
			(at -0.939 5.799 0)
			(layer "F.Fab")
			(effects
				(font
					(size 0.7 0.7)
					(thickness 0.15)
				)
				(justify left bottom)
			)
		)
		(pad "1" smd roundrect
			(at -0.48 0)
			(size 0.59 0.64)
			(layers "F.Cu" "F.Mask" "F.Paste")
			(roundrect_rratio 0.25)
			(net 66 "GND")
			(pintype "passive")
		)
		(pad "2" smd roundrect
			(at 0.48 0)
			(size 0.59 0.64)
			(layers "F.Cu" "F.Mask" "F.Paste")
			(roundrect_rratio 0.25)
			(net 117 "/USB-PD/VDDD_3V3")
			(pintype "passive")
		)
	)
	(footprint "antmicro-footprints:R_0402_1005Metric"
		(layer "F.Cu")
		(at 148.152 88)
		(descr "Resistor SMD 0402")
		(tags "resistor SMD 0402")
		(property "Reference" "R34"
			(at 1.248 0.3 180)
			(layer "F.SilkS")
			(effects
				(font
					(size 0.7 0.7)
					(thickness 0.15)
				)
				(justify left bottom)
			)
		)
		(property "Value" "R_100k_0402"
			(at -1.011843 1.772046 0)
			(layer "F.Fab")
			(effects
				(font
					(size 0.7 0.7)
					(thickness 0.15)
				)
				(justify left bottom)
			)
		)
		(property "Datasheet" "https://www.bourns.com/docs/product-datasheets/cr.pdf"
			(at 0 0 0)
			(layer "F.Fab")
			(hide yes)
			(effects
				(font
					(size 1.27 1.27)
					(thickness 0.15)
				)
			)
		)
		(property "Description" "SMD Chip Resistor, 100 kohm, ± 1%, 62.5 mW, 0402 [1005 Metric], Thick Film, General Purpose"
			(at 0 0 0)
			(layer "F.Fab")
			(hide yes)
			(effects
				(font
					(size 1.27 1.27)
					(thickness 0.15)
				)
			)
		)
		(property "Manufacturer" "Bourns"
			(at 0 0 0)
			(unlocked yes)
			(layer "F.Fab")
			(hide yes)
			(effects
				(font
					(size 1 1)
					(thickness 0.15)
				)
			)
		)
		(property "MPN" "CR0402-FX-1003GLF"
			(at 0 0 0)
			(unlocked yes)
			(layer "F.Fab")
			(hide yes)
			(effects
				(font
					(size 1 1)
					(thickness 0.15)
				)
			)
		)
		(property "Val" "100k"
			(at 0 0 0)
			(unlocked yes)
			(layer "F.Fab")
			(hide yes)
			(effects
				(font
					(size 1 1)
					(thickness 0.15)
				)
			)
		)
		(property "License" "Apache-2.0"
			(at 0 0 0)
			(unlocked yes)
			(layer "F.Fab")
			(hide yes)
			(effects
				(font
					(size 1 1)
					(thickness 0.15)
				)
			)
		)
		(property "Author" "Antmicro"
			(at 0 0 0)
			(unlocked yes)
			(layer "F.Fab")
			(hide yes)
			(effects
				(font
					(size 1 1)
					(thickness 0.15)
				)
			)
		)
		(property "Tolerance" "1%"
			(at 0 0 0)
			(unlocked yes)
			(layer "F.Fab")
			(hide yes)
			(effects
				(font
					(size 1 1)
					(thickness 0.15)
				)
			)
		)
		(sheetname "/USB-PD/")
		(sheetfile "usb-pd.kicad_sch")
		(attr smd)
		(fp_rect
			(start -0.925 -0.47)
			(end 0.925 0.47)
			(stroke
				(width 0.05)
				(type default)
			)
			(fill no)
			(layer "F.CrtYd")
		)
		(fp_rect
			(start -0.5 -0.25)
			(end 0.5 0.25)
			(stroke
				(width 0.15)
				(type solid)
			)
			(fill no)
			(layer "F.Fab")
		)
		(fp_text user "${REFERENCE}"
			(at 0 0 0)
			(layer "F.Fab")
			(effects
				(font
					(size 0.7 0.7)
					(thickness 0.15)
				)
				(justify left bottom)
			)
		)
		(fp_text user "Author: Antmicro"
			(at -0.95 4.169 0)
			(layer "F.Fab")
			(effects
				(font
					(size 0.7 0.7)
					(thickness 0.15)
				)
				(justify left bottom)
			)
		)
		(fp_text user "License: Apache-2.0"
			(at -0.949999 5.169 0)
			(layer "F.Fab")
			(effects
				(font
					(size 0.7 0.7)
					(thickness 0.15)
				)
				(justify left bottom)
			)
		)
		(pad "1" smd roundrect
			(at -0.48 0)
			(size 0.59 0.64)
			(layers "F.Cu" "F.Mask" "F.Paste")
			(roundrect_rratio 0.25)
			(net 158 "/USB-PD/12V_PG")
			(pintype "passive")
		)
		(pad "2" smd roundrect
			(at 0.48 0)
			(size 0.59 0.64)
			(layers "F.Cu" "F.Mask" "F.Paste")
			(roundrect_rratio 0.25)
			(net 121 "/USB-PD/12V_VDD")
			(pintype "passive")
		)
	)
)
